(kicad_pcb
	(version 20260206)
	(generator "pcbnew")
	(generator_version "10.0")
	(general
		(thickness 1.6)
		(legacy_teardrops no)
	)
	(paper "A4")
	(title_block
		(title "Wiwynn_Tioga_Pass_MB.brd")
		(comment 1 "Tioga Pass / footprints 4370-4376 of 4770")
	)
	(layers
		(0 "F.Cu" signal "TOP")
		(4 "In1.Cu" signal "L2GND")
		(6 "In2.Cu" signal "L3")
		(8 "In3.Cu" signal "L4GND")
		(10 "In4.Cu" signal "L5")
		(12 "In5.Cu" signal "L6GND")
		(14 "In6.Cu" signal "L7VCC")
		(16 "In7.Cu" signal "L8VCC")
		(18 "In8.Cu" signal "L9GND")
		(20 "In9.Cu" signal "L10")
		(22 "In10.Cu" signal "L11GND")
		(24 "In11.Cu" signal "L12")
		(26 "In12.Cu" signal "L13GND")
		(2 "B.Cu" signal "BOTTOM")
		(9 "F.Adhes" user "F.Adhesive")
		(11 "B.Adhes" user "B.Adhesive")
		(13 "F.Paste" user "Package Geometry/Pastemask Top")
		(15 "B.Paste" user "Package Geometry/Pastemask Bottom")
		(5 "F.SilkS" user "Ref Des/Silkscreen Top")
		(7 "B.SilkS" user "Ref Des/Silkscreen Bottom")
		(1 "F.Mask" user "Board Geometry/Soldermask Top")
		(3 "B.Mask" user "Board Geometry/Soldermask Bottom")
		(17 "Dwgs.User" user "User.Drawings")
		(19 "Cmts.User" user "User.Comments")
		(21 "Eco1.User" user "User.Eco1")
		(23 "Eco2.User" user "User.Eco2")
		(25 "Edge.Cuts" user "Board Geometry/Outline")
		(27 "Margin" user)
		(31 "F.CrtYd" user "Package Geometry/Place Bound Top")
		(29 "B.CrtYd" user "Package Geometry/Place Bound Bottom")
		(35 "F.Fab" user "Ref Des/Assembly Top")
		(33 "B.Fab" user "Ref Des/Assembly Bottom")
	)
	(footprint ""
		(layer "B.Cu")
		(at 464.3755 -126.492 -90)
		(property "Reference" "C1M38"
			(at 0 0 90)
			(layer "B.SilkS")
			(hide yes)
			(effects
				(font
					(size 1.27 1.27)
				)
				(justify mirror)
			)
		)
		(property "Value" ""
			(at 0 0 90)
			(layer "B.Fab")
			(effects
				(font
					(size 1.27 1.27)
				)
				(justify mirror)
			)
		)
		(duplicate_pad_numbers_are_jumpers no)
		(fp_rect
			(start -0.3048 -0.1016)
			(end 0.3048 0.9906)
			(stroke
				(width 0)
				(type default)
			)
			(fill no)
			(layer "B.CrtYd")
		)
		(fp_line
			(start -0.3048 0.9906)
			(end -0.3048 -0.1016)
			(stroke
				(width 0.1)
				(type default)
			)
			(layer "B.Fab")
		)
		(fp_line
			(start 0.3048 0.9906)
			(end -0.3048 0.9906)
			(stroke
				(width 0.1)
				(type default)
			)
			(layer "B.Fab")
		)
		(fp_line
			(start -0.3048 -0.1016)
			(end 0.3048 -0.1016)
			(stroke
				(width 0.1)
				(type default)
			)
			(layer "B.Fab")
		)
		(fp_line
			(start 0.3048 -0.1016)
			(end 0.3048 0.9906)
			(stroke
				(width 0.1)
				(type default)
			)
			(layer "B.Fab")
		)
		(pad "1" smd rect
			(at 0 0 90)
			(size 0.508 0.508)
			(layers "B.Cu" "B.Mask" "B.Paste")
			(net "P5V_TPS2061")
		)
		(pad "2" smd rect
			(at 0 0.889 90)
			(size 0.508 0.508)
			(layers "B.Cu" "B.Mask" "B.Paste")
			(net "GND")
		)
		(zone
			(layer "B.Cu")
			(hatch none 0.5)
			(connect_pads
				(clearance 0)
			)
			(min_thickness 0.25)
			(keepout
				(tracks allowed)
				(vias not_allowed)
				(pads allowed)
				(copperpour not_allowed)
				(footprints allowed)
			)
			(placement
				(enabled no)
				(sheetname "")
			)
			(fill
				(thermal_gap 0.5)
				(thermal_bridge_width 0.5)
				(island_removal_mode 0)
			)
			(polygon
				(pts
					(xy 464.1215 -126.746) (xy 463.7405 -126.746) (xy 463.7405 -126.238) (xy 464.1215 -126.238)
				)
			)
		)
		(zone
			(layer "B.Cu")
			(hatch none 0.5)
			(connect_pads
				(clearance 0)
			)
			(min_thickness 0.25)
			(keepout
				(tracks not_allowed)
				(vias allowed)
				(pads allowed)
				(copperpour not_allowed)
				(footprints allowed)
			)
			(placement
				(enabled no)
				(sheetname "")
			)
			(fill
				(thermal_gap 0.5)
				(thermal_bridge_width 0.5)
				(island_removal_mode 0)
			)
			(polygon
				(pts
					(xy 464.1215 -126.746) (xy 463.7405 -126.746) (xy 463.7405 -126.238) (xy 464.1215 -126.238)
				)
			)
		)
	)
	(footprint ""
		(layer "B.Cu")
		(at 499.2878 -145.9738 180)
		(property "Reference" "R1L21"
			(at 0 0 0)
			(layer "B.SilkS")
			(hide yes)
			(effects
				(font
					(size 1.27 1.27)
				)
				(justify mirror)
			)
		)
		(property "Value" ""
			(at 0 0 0)
			(layer "B.Fab")
			(effects
				(font
					(size 1.27 1.27)
				)
				(justify mirror)
			)
		)
		(duplicate_pad_numbers_are_jumpers no)
		(fp_poly
			(pts
				(xy 0.2794 -0.1016) (xy -0.2794 -0.1016) (xy -0.2794 0.9906) (xy 0.2794 0.9906)
			)
			(stroke
				(width 0)
				(type default)
			)
			(fill no)
			(layer "B.CrtYd")
		)
		(fp_line
			(start 0.2794 0.9906)
			(end -0.2794 0.9906)
			(stroke
				(width 0.1)
				(type default)
			)
			(layer "B.Fab")
		)
		(fp_line
			(start 0.2794 -0.1016)
			(end 0.2794 0.9906)
			(stroke
				(width 0.1)
				(type default)
			)
			(layer "B.Fab")
		)
		(fp_line
			(start -0.2794 0.9906)
			(end -0.2794 -0.1016)
			(stroke
				(width 0.1)
				(type default)
			)
			(layer "B.Fab")
		)
		(fp_line
			(start -0.2794 -0.1016)
			(end 0.2794 -0.1016)
			(stroke
				(width 0.1)
				(type default)
			)
			(layer "B.Fab")
		)
		(pad "1" smd rect
			(at 0 0)
			(size 0.508 0.508)
			(layers "B.Cu" "B.Mask" "B.Paste")
			(net "P3V3")
		)
		(pad "2" smd rect
			(at 0 0.889)
			(size 0.508 0.508)
			(layers "B.Cu" "B.Mask" "B.Paste")
			(net "FP_LED_HDD_ACTIVITY_AND_R_N")
		)
		(zone
			(layer "B.Cu")
			(hatch none 0.5)
			(connect_pads
				(clearance 0)
			)
			(min_thickness 0.25)
			(keepout
				(tracks not_allowed)
				(vias allowed)
				(pads allowed)
				(copperpour not_allowed)
				(footprints allowed)
			)
			(placement
				(enabled no)
				(sheetname "")
			)
			(fill
				(thermal_gap 0.5)
				(thermal_bridge_width 0.5)
				(island_removal_mode 0)
			)
			(polygon
				(pts
					(xy 499.0338 -146.6088) (xy 499.5418 -146.6088) (xy 499.5418 -146.2278) (xy 499.0338 -146.2278)
				)
			)
		)
		(zone
			(layer "B.Cu")
			(hatch none 0.5)
			(connect_pads
				(clearance 0)
			)
			(min_thickness 0.25)
			(keepout
				(tracks allowed)
				(vias not_allowed)
				(pads allowed)
				(copperpour not_allowed)
				(footprints allowed)
			)
			(placement
				(enabled no)
				(sheetname "")
			)
			(fill
				(thermal_gap 0.5)
				(thermal_bridge_width 0.5)
				(island_removal_mode 0)
			)
			(polygon
				(pts
					(xy 499.0338 -146.2278) (xy 499.5418 -146.2278) (xy 499.5418 -146.6088) (xy 499.0338 -146.6088)
				)
			)
		)
	)
	(footprint ""
		(layer "B.Cu")
		(at 450.7484 -9.6012 -90)
		(property "Reference" "CR2U1"
			(at 1.93167 -1.016 0)
			(unlocked yes)
			(layer "B.SilkS")
			(effects
				(font
					(size 0.7874 0.5842)
					(thickness 0.1524)
				)
				(justify left mirror)
			)
		)
		(property "Value" ""
			(at 0 0 90)
			(layer "B.Fab")
			(effects
				(font
					(size 1.27 1.27)
				)
				(justify mirror)
			)
		)
		(duplicate_pad_numbers_are_jumpers no)
		(fp_line
			(start -1.8415 2.5273)
			(end -0.9652 2.5273)
			(stroke
				(width 0.1524)
				(type default)
			)
			(layer "B.SilkS")
		)
		(fp_line
			(start -1.8415 1.8542)
			(end -1.8415 2.5273)
			(stroke
				(width 0.1524)
				(type default)
			)
			(layer "B.SilkS")
		)
		(fp_line
			(start -1.8415 -0.4953)
			(end -1.8415 0.1778)
			(stroke
				(width 0.1524)
				(type default)
			)
			(layer "B.SilkS")
		)
		(fp_line
			(start -0.9652 -0.4953)
			(end -1.8415 -0.4953)
			(stroke
				(width 0.1524)
				(type default)
			)
			(layer "B.SilkS")
		)
		(fp_circle
			(center 0.988568 -1.098296)
			(end 0.988568 -1.225296)
			(stroke
				(width 0.254)
				(type default)
			)
			(fill no)
			(layer "B.SilkS")
		)
		(fp_poly
			(pts
				(xy -1.8415 2.5273) (xy -0.4445 2.5273) (xy -0.4445 -0.4953) (xy -1.8415 -0.4953)
			)
			(stroke
				(width 0)
				(type default)
			)
			(fill no)
			(layer "B.CrtYd")
		)
		(fp_rect
			(start -1.8415 2.5273)
			(end -0.4445 -0.4953)
			(stroke
				(width 0)
				(type default)
			)
			(fill no)
			(layer "B.Fab")
		)
		(fp_circle
			(center 0.988568 -1.098296)
			(end 0.988568 -1.225296)
			(stroke
				(width 0.254)
				(type default)
			)
			(fill no)
			(layer "B.Fab")
		)
		(pad "1" smd rect
			(at 0 0 90)
			(size 1.27 1.016)
			(layers "B.Cu" "B.Mask" "B.Paste")
			(net "P3V3_STBY")
		)
		(pad "2" smd rect
			(at 0 2.032 90)
			(size 1.27 1.016)
			(layers "B.Cu" "B.Mask" "B.Paste")
			(net "A_P3V_BAT_R")
		)
		(pad "3" smd rect
			(at -2.286 1.016 90)
			(size 1.27 1.016)
			(layers "B.Cu" "B.Mask" "B.Paste")
			(net "P3V3_RTC_STBY")
		)
	)
	(footprint ""
		(layer "B.Cu")
		(at 471.3605 -137.795 -90)
		(property "Reference" "R1L31"
			(at 0 0 90)
			(layer "B.SilkS")
			(hide yes)
			(effects
				(font
					(size 1.27 1.27)
				)
				(justify mirror)
			)
		)
		(property "Value" ""
			(at 0 0 90)
			(layer "B.Fab")
			(effects
				(font
					(size 1.27 1.27)
				)
				(justify mirror)
			)
		)
		(duplicate_pad_numbers_are_jumpers no)
		(fp_poly
			(pts
				(xy 0.2794 -0.1016) (xy -0.2794 -0.1016) (xy -0.2794 0.9906) (xy 0.2794 0.9906)
			)
			(stroke
				(width 0)
				(type default)
			)
			(fill no)
			(layer "B.CrtYd")
		)
		(fp_line
			(start -0.2794 0.9906)
			(end -0.2794 -0.1016)
			(stroke
				(width 0.1)
				(type default)
			)
			(layer "B.Fab")
		)
		(fp_line
			(start 0.2794 0.9906)
			(end -0.2794 0.9906)
			(stroke
				(width 0.1)
				(type default)
			)
			(layer "B.Fab")
		)
		(fp_line
			(start -0.2794 -0.1016)
			(end 0.2794 -0.1016)
			(stroke
				(width 0.1)
				(type default)
			)
			(layer "B.Fab")
		)
		(fp_line
			(start 0.2794 -0.1016)
			(end 0.2794 0.9906)
			(stroke
				(width 0.1)
				(type default)
			)
			(layer "B.Fab")
		)
		(pad "1" smd rect
			(at 0 0 90)
			(size 0.508 0.508)
			(layers "B.Cu" "B.Mask" "B.Paste")
			(net "FP_PWR_BTN_R_N")
		)
		(pad "2" smd rect
			(at 0 0.889 90)
			(size 0.508 0.508)
			(layers "B.Cu" "B.Mask" "B.Paste")
			(net "FP_PWR_BTN_R1_N")
		)
		(zone
			(layer "B.Cu")
			(hatch none 0.5)
			(connect_pads
				(clearance 0)
			)
			(min_thickness 0.25)
			(keepout
				(tracks not_allowed)
				(vias allowed)
				(pads allowed)
				(copperpour not_allowed)
				(footprints allowed)
			)
			(placement
				(enabled no)
				(sheetname "")
			)
			(fill
				(thermal_gap 0.5)
				(thermal_bridge_width 0.5)
				(island_removal_mode 0)
			)
			(polygon
				(pts
					(xy 470.7255 -137.541) (xy 470.7255 -138.049) (xy 471.1065 -138.049) (xy 471.1065 -137.541)
				)
			)
		)
		(zone
			(layer "B.Cu")
			(hatch none 0.5)
			(connect_pads
				(clearance 0)
			)
			(min_thickness 0.25)
			(keepout
				(tracks allowed)
				(vias not_allowed)
				(pads allowed)
				(copperpour not_allowed)
				(footprints allowed)
			)
			(placement
				(enabled no)
				(sheetname "")
			)
			(fill
				(thermal_gap 0.5)
				(thermal_bridge_width 0.5)
				(island_removal_mode 0)
			)
			(polygon
				(pts
					(xy 471.1065 -137.541) (xy 471.1065 -138.049) (xy 470.7255 -138.049) (xy 470.7255 -137.541)
				)
			)
		)
	)
	(footprint ""
		(layer "B.Cu")
		(at 45.212 -83.947 -90)
		(property "Reference" "C9P5"
			(at 0.78867 -3.556 0)
			(unlocked yes)
			(layer "B.SilkS")
			(effects
				(font
					(size 0.7874 0.5842)
					(thickness 0.1524)
				)
				(justify mirror)
			)
		)
		(property "Value" ""
			(at 0 0 90)
			(layer "B.Fab")
			(effects
				(font
					(size 1.27 1.27)
				)
				(justify mirror)
			)
		)
		(duplicate_pad_numbers_are_jumpers no)
		(fp_line
			(start -2.286 7.366)
			(end -1.600708 7.366)
			(stroke
				(width 0.1524)
				(type default)
			)
			(layer "B.SilkS")
		)
		(fp_line
			(start -2.286 7.366)
			(end -2.286 1.63195)
			(stroke
				(width 0.1524)
				(type default)
			)
			(layer "B.SilkS")
		)
		(fp_line
			(start 2.286 7.366)
			(end 1.60147 7.366)
			(stroke
				(width 0.1524)
				(type default)
			)
			(layer "B.SilkS")
		)
		(fp_line
			(start 2.286 7.366)
			(end 2.286 1.632712)
			(stroke
				(width 0.1524)
				(type default)
			)
			(layer "B.SilkS")
		)
		(fp_line
			(start -2.504948 1.633728)
			(end -1.6002 1.633728)
			(stroke
				(width 0.1524)
				(type default)
			)
			(layer "B.SilkS")
		)
		(fp_line
			(start 2.563114 1.633728)
			(end 1.6002 1.633728)
			(stroke
				(width 0.1524)
				(type default)
			)
			(layer "B.SilkS")
		)
		(fp_line
			(start -2.504948 -1.616456)
			(end -2.504948 1.633728)
			(stroke
				(width 0.1524)
				(type default)
			)
			(layer "B.SilkS")
		)
		(fp_line
			(start -1.6002 -1.616456)
			(end -2.504948 -1.616456)
			(stroke
				(width 0.1524)
				(type default)
			)
			(layer "B.SilkS")
		)
		(fp_line
			(start 1.6002 -1.616456)
			(end 2.563114 -1.616456)
			(stroke
				(width 0.1524)
				(type default)
			)
			(layer "B.SilkS")
		)
		(fp_line
			(start 2.563114 -1.616456)
			(end 2.563114 1.633728)
			(stroke
				(width 0.1524)
				(type default)
			)
			(layer "B.SilkS")
		)
		(fp_rect
			(start 2.286 7.366)
			(end -2.286 -0.254)
			(stroke
				(width 0)
				(type default)
			)
			(fill no)
			(layer "B.CrtYd")
		)
		(fp_line
			(start -2.286 7.366)
			(end 2.286 7.366)
			(stroke
				(width 0.1)
				(type default)
			)
			(layer "B.Fab")
		)
		(fp_line
			(start 2.286 7.366)
			(end 2.286 -0.254)
			(stroke
				(width 0.1)
				(type default)
			)
			(layer "B.Fab")
		)
		(fp_line
			(start -2.286 -0.254)
			(end -2.286 7.366)
			(stroke
				(width 0.1)
				(type default)
			)
			(layer "B.Fab")
		)
		(fp_line
			(start 2.286 -0.254)
			(end -2.286 -0.254)
			(stroke
				(width 0.1)
				(type default)
			)
			(layer "B.Fab")
		)
		(pad "1" smd rect
			(at 0 0 90)
			(size 2.54 3.048)
			(layers "B.Cu" "B.Mask" "B.Paste")
			(net "PVCCIN_CPU1")
		)
		(pad "2" smd rect
			(at 0 7.112 90)
			(size 2.54 3.048)
			(layers "B.Cu" "B.Mask" "B.Paste")
			(net "GND")
		)
	)
	(footprint ""
		(layer "B.Cu")
		(at 179.199794 -69.230494 -90)
		(property "Reference" "R6P32"
			(at 0 0 90)
			(layer "B.SilkS")
			(hide yes)
			(effects
				(font
					(size 1.27 1.27)
				)
				(justify mirror)
			)
		)
		(property "Value" ""
			(at 0 0 90)
			(layer "B.Fab")
			(effects
				(font
					(size 1.27 1.27)
				)
				(justify mirror)
			)
		)
		(duplicate_pad_numbers_are_jumpers no)
		(fp_rect
			(start 0.2794 0.9906)
			(end -0.2794 -0.1016)
			(stroke
				(width 0)
				(type default)
			)
			(fill no)
			(layer "B.CrtYd")
		)
		(fp_line
			(start -0.2794 0.9906)
			(end -0.2794 -0.1016)
			(stroke
				(width 0.1)
				(type default)
			)
			(layer "B.Fab")
		)
		(fp_line
			(start 0.2794 0.9906)
			(end -0.2794 0.9906)
			(stroke
				(width 0.1)
				(type default)
			)
			(layer "B.Fab")
		)
		(fp_line
			(start -0.2794 -0.1016)
			(end 0.2794 -0.1016)
			(stroke
				(width 0.1)
				(type default)
			)
			(layer "B.Fab")
		)
		(fp_line
			(start 0.2794 -0.1016)
			(end 0.2794 0.9906)
			(stroke
				(width 0.1)
				(type default)
			)
			(layer "B.Fab")
		)
		(pad "1" smd rect
			(at 0 0 90)
			(size 0.508 0.508)
			(layers "B.Cu" "B.Mask" "B.Paste")
			(net "P3V3_STBY")
		)
		(pad "2" smd rect
			(at 0 0.889 90)
			(size 0.508 0.508)
			(layers "B.Cu" "B.Mask" "B.Paste")
			(net "SMB_VR_STBY_LVC3_SDA")
		)
		(zone
			(layer "B.Cu")
			(hatch none 0.5)
			(connect_pads
				(clearance 0)
			)
			(min_thickness 0.25)
			(keepout
				(tracks not_allowed)
				(vias allowed)
				(pads allowed)
				(copperpour not_allowed)
				(footprints allowed)
			)
			(placement
				(enabled no)
				(sheetname "")
			)
			(fill
				(thermal_gap 0.5)
				(thermal_bridge_width 0.5)
				(island_removal_mode 0)
			)
			(polygon
				(pts
					(xy 178.564794 -68.976494) (xy 178.945794 -68.976494) (xy 178.945794 -69.484494) (xy 178.564794 -69.484494)
				)
			)
		)
		(zone
			(layer "B.Cu")
			(hatch none 0.5)
			(connect_pads
				(clearance 0)
			)
			(min_thickness 0.25)
			(keepout
				(tracks allowed)
				(vias not_allowed)
				(pads allowed)
				(copperpour not_allowed)
				(footprints allowed)
			)
			(placement
				(enabled no)
				(sheetname "")
			)
			(fill
				(thermal_gap 0.5)
				(thermal_bridge_width 0.5)
				(island_removal_mode 0)
			)
			(polygon
				(pts
					(xy 178.564794 -68.976494) (xy 178.945794 -68.976494) (xy 178.945794 -69.484494) (xy 178.564794 -69.484494)
				)
			)
		)
	)
	(footprint ""
		(layer "B.Cu")
		(at 442.849 -116.49202)
		(property "Reference" "C2M15"
			(at 0 0 0)
			(layer "B.SilkS")
			(hide yes)
			(effects
				(font
					(size 1.27 1.27)
				)
				(justify mirror)
			)
		)
		(property "Value" ""
			(at 0 0 0)
			(layer "B.Fab")
			(effects
				(font
					(size 1.27 1.27)
				)
				(justify mirror)
			)
		)
		(duplicate_pad_numbers_are_jumpers no)
		(fp_rect
			(start -0.3048 0.9906)
			(end 0.3048 -0.1016)
			(stroke
				(width 0)
				(type default)
			)
			(fill no)
			(layer "B.CrtYd")
		)
		(fp_line
			(start -0.3048 -0.1016)
			(end 0.3048 -0.1016)
			(stroke
				(width 0.1)
				(type default)
			)
			(layer "B.Fab")
		)
		(fp_line
			(start -0.3048 0.9906)
			(end -0.3048 -0.1016)
			(stroke
				(width 0.1)
				(type default)
			)
			(layer "B.Fab")
		)
		(fp_line
			(start 0.3048 -0.1016)
			(end 0.3048 0.9906)
			(stroke
				(width 0.1)
				(type default)
			)
			(layer "B.Fab")
		)
		(fp_line
			(start 0.3048 0.9906)
			(end -0.3048 0.9906)
			(stroke
				(width 0.1)
				(type default)
			)
			(layer "B.Fab")
		)
		(pad "1" smd rect
			(at 0 0 180)
			(size 0.508 0.508)
			(layers "B.Cu" "B.Mask" "B.Paste")
			(net "P3E_CPU0_PE3_OCP_TXN<8>")
		)
		(pad "2" smd rect
			(at 0 0.889 180)
			(size 0.508 0.508)
			(layers "B.Cu" "B.Mask" "B.Paste")
			(net "P3E_OCP_CPU0_PE3_C_TXN<8>")
		)
		(zone
			(layer "B.Cu")
			(hatch none 0.5)
			(connect_pads
				(clearance 0)
			)
			(min_thickness 0.25)
			(keepout
				(tracks not_allowed)
				(vias allowed)
				(pads allowed)
				(copperpour not_allowed)
				(footprints allowed)
			)
			(placement
				(enabled no)
				(sheetname "")
			)
			(fill
				(thermal_gap 0.5)
				(thermal_bridge_width 0.5)
				(island_removal_mode 0)
			)
			(polygon
				(pts
					(xy 442.595 -115.85702) (xy 443.103 -115.85702) (xy 443.103 -116.23802) (xy 442.595 -116.23802)
				)
			)
		)
		(zone
			(layer "B.Cu")
			(hatch none 0.5)
			(connect_pads
				(clearance 0)
			)
			(min_thickness 0.25)
			(keepout
				(tracks allowed)
				(vias not_allowed)
				(pads allowed)
				(copperpour not_allowed)
				(footprints allowed)
			)
			(placement
				(enabled no)
				(sheetname "")
			)
			(fill
				(thermal_gap 0.5)
				(thermal_bridge_width 0.5)
				(island_removal_mode 0)
			)
			(polygon
				(pts
					(xy 442.595 -115.85702) (xy 443.103 -115.85702) (xy 443.103 -116.23802) (xy 442.595 -116.23802)
				)
			)
		)
	)
)
